# TIMECARD (Time Appliance Project (Time Card)) — schematic netlist excerpt (pin names and nets, part order shuffled) for the footprints in the layout excerpt that follows; sources: Cadence DE-HDL packaged netlist, KiCad conversion of R4006-B0001-02_R01.brd

C243  CAPACITOR  22UF 10V 20%  pkg SMC_0805R_H057  page 31 : \1\ = XP3R3V_FPGA ; \2\ = SG
R417  RESISTOR  1KOHM 1%  pkg SMC_0402R_H016  page 17 : \1\ = UNNAMED_6_LM75BDPTSSOP8_I81_A0 ; \2\ = SG

(kicad_pcb
	(version 20260206)
	(generator "pcbnew")
	(generator_version "10.0")
	(general
		(thickness 1.6)
		(legacy_teardrops no)
	)
	(paper "A4")
	(title_block
		(title "timecard-production-celestica-r4006 — R4006-B0001-02_R01.brd")
		(comment 1 "Time Appliance Project (Time Card) / footprints 675-676 of 1113")
	)
	(layers
		(0 "F.Cu" signal "TOP")
		(4 "In1.Cu" signal "L02_GND1")
		(6 "In2.Cu" signal "L03_SIG1")
		(8 "In3.Cu" signal "L04_GND2")
		(10 "In4.Cu" signal "L05_VCC1")
		(12 "In5.Cu" signal "L06_VCC2")
		(14 "In6.Cu" signal "L07_GND3")
		(16 "In7.Cu" signal "L08_SIG2")
		(18 "In8.Cu" signal "L09_GND4")
		(2 "B.Cu" signal "BOTTOM")
		(9 "F.Adhes" user "F.Adhesive")
		(11 "B.Adhes" user "B.Adhesive")
		(13 "F.Paste" user "Package Geometry/Pastemask Top")
		(15 "B.Paste" user "Package Geometry/Pastemask Bottom")
		(5 "F.SilkS" user "Ref Des/Silkscreen Top")
		(7 "B.SilkS" user "Ref Des/Silkscreen Bottom")
		(1 "F.Mask" user "Board Geometry/Soldermask Top")
		(3 "B.Mask" user "Board Geometry/Soldermask Bottom")
		(17 "Dwgs.User" user "User.Drawings")
		(19 "Cmts.User" user "User.Comments")
		(21 "Eco1.User" user "User.Eco1")
		(23 "Eco2.User" user "User.Eco2")
		(25 "Edge.Cuts" user "Board Geometry/Outline")
		(27 "Margin" user)
		(31 "F.CrtYd" user "Package Geometry/Place Bound Top")
		(29 "B.CrtYd" user "Package Geometry/Place Bound Bottom")
		(35 "F.Fab" user "Ref Des/Assembly Top")
		(33 "B.Fab" user "Ref Des/Assembly Bottom")
	)
	(footprint ""
		(layer "B.Cu")
		(at 162.56 -27.432 180)
		(property "Reference" "R417"
			(at 0.508 2.11963 0)
			(unlocked yes)
			(layer "B.SilkS")
			(effects
				(font
					(size 0.7874 0.5842)
					(thickness 0.1524)
				)
				(justify mirror)
			)
		)
		(property "Value" "VAL*"
			(at -0.02032 2.13233 180)
			(unlocked yes)
			(layer "B.Fab")
			(hide yes)
			(effects
				(font
					(size 0.7874 0.5842)
					(thickness 0.1524)
				)
				(justify mirror)
			)
		)
		(property "Tolerance" "TOL*"
			(at -0.044704 3.05435 180)
			(unlocked yes)
			(layer "Cmts.User")
			(hide yes)
			(effects
				(font
					(size 0.7874 0.5842)
					(thickness 0.1524)
				)
				(justify mirror)
			)
		)
		(property "User Part Number" "PARTNUM*"
			(at -0.02032 4.024884 180)
			(unlocked yes)
			(layer "Cmts.User")
			(hide yes)
			(effects
				(font
					(size 0.7874 0.5842)
					(thickness 0.1524)
				)
				(justify mirror)
			)
		)
		(property "Device Type" "RESISTOR-G155-11001-01,1KOHM,1%"
			(at -0.008382 1.210564 180)
			(unlocked yes)
			(layer "B.Fab")
			(hide yes)
			(effects
				(font
					(size 0.7874 0.5842)
					(thickness 0.1524)
				)
				(justify mirror)
			)
		)
		(duplicate_pad_numbers_are_jumpers no)
		(fp_line
			(start 1.143 0.5588)
			(end -1.143 0.5588)
			(stroke
				(width 0.1)
				(type default)
			)
			(layer "B.SilkS")
		)
		(fp_line
			(start 1.143 -0.5588)
			(end 1.143 0.5588)
			(stroke
				(width 0.1)
				(type default)
			)
			(layer "B.SilkS")
		)
		(fp_line
			(start -1.143 0.5588)
			(end -1.143 -0.5588)
			(stroke
				(width 0.1)
				(type default)
			)
			(layer "B.SilkS")
		)
		(fp_line
			(start -1.143 -0.5588)
			(end 1.143 -0.5588)
			(stroke
				(width 0.1)
				(type default)
			)
			(layer "B.SilkS")
		)
		(fp_rect
			(start 1.143 -0.5588)
			(end -1.143 0.5588)
			(stroke
				(width 0)
				(type default)
			)
			(fill no)
			(layer "B.CrtYd")
		)
		(fp_line
			(start 0.508 0.3048)
			(end -0.508 0.3048)
			(stroke
				(width 0.1)
				(type default)
			)
			(layer "B.Fab")
		)
		(fp_line
			(start 0.508 -0.3048)
			(end 0.508 0.3048)
			(stroke
				(width 0.1)
				(type default)
			)
			(layer "B.Fab")
		)
		(fp_line
			(start -0.508 0.3048)
			(end -0.508 -0.3048)
			(stroke
				(width 0.1)
				(type default)
			)
			(layer "B.Fab")
		)
		(fp_line
			(start -0.508 -0.3048)
			(end 0.508 -0.3048)
			(stroke
				(width 0.1)
				(type default)
			)
			(layer "B.Fab")
		)
		(pad "1" smd rect
			(at 0.5334 0)
			(size 0.7112 0.6096)
			(layers "B.Cu" "B.Mask" "B.Paste")
			(net "UNNAMED_6_LM75BDPTSSOP8_I81_A0")
		)
		(pad "2" smd rect
			(at -0.5334 0)
			(size 0.7112 0.6096)
			(layers "B.Cu" "B.Mask" "B.Paste")
			(net "SG")
		)
		(zone
			(layer "B.Cu")
			(hatch none 0.5)
			(connect_pads
				(clearance 0)
			)
			(min_thickness 0.25)
			(keepout
				(tracks not_allowed)
				(vias allowed)
				(pads allowed)
				(copperpour not_allowed)
				(footprints allowed)
			)
			(placement
				(enabled no)
				(sheetname "")
			)
			(fill
				(thermal_gap 0.5)
				(thermal_bridge_width 0.5)
				(island_removal_mode 0)
			)
			(polygon
				(pts
					(xy 162.4838 -27.1272) (xy 162.6362 -27.1272) (xy 162.6362 -27.7368) (xy 162.4838 -27.7368)
				)
			)
		)
		(zone
			(layer "B.Cu")
			(hatch none 0.5)
			(connect_pads
				(clearance 0)
			)
			(min_thickness 0.25)
			(keepout
				(tracks allowed)
				(vias not_allowed)
				(pads allowed)
				(copperpour not_allowed)
				(footprints allowed)
			)
			(placement
				(enabled no)
				(sheetname "")
			)
			(fill
				(thermal_gap 0.5)
				(thermal_bridge_width 0.5)
				(island_removal_mode 0)
			)
			(polygon
				(pts
					(xy 162.4838 -27.1272) (xy 162.6362 -27.1272) (xy 162.6362 -27.7368) (xy 162.4838 -27.7368)
				)
			)
		)
	)
	(footprint ""
		(layer "B.Cu")
		(at 105.8418 -72.517)
		(property "Reference" "C243"
			(at -3.81 -0.08763 0)
			(unlocked yes)
			(layer "B.SilkS")
			(effects
				(font
					(size 0.7874 0.5842)
					(thickness 0.1524)
				)
				(justify mirror)
			)
		)
		(property "Value" "VAL*"
			(at -0.0762 3.134106 0)
			(unlocked yes)
			(layer "B.Fab")
			(hide yes)
			(effects
				(font
					(size 0.7874 0.5842)
					(thickness 0.1524)
				)
				(justify mirror)
			)
		)
		(property "Device Type" "CAPACITOR-G107-0F226-CM,22UF,2A"
			(at -0.0508 2.194306 0)
			(unlocked yes)
			(layer "B.Fab")
			(hide yes)
			(effects
				(font
					(size 0.7874 0.5842)
					(thickness 0.1524)
				)
				(justify mirror)
			)
		)
		(property "User Part Number" "PARTNUM*"
			(at -0.1016 5.013706 0)
			(unlocked yes)
			(layer "Cmts.User")
			(hide yes)
			(effects
				(font
					(size 0.7874 0.5842)
					(thickness 0.1524)
				)
				(justify mirror)
			)
		)
		(property "Tolerance" "TOL*"
			(at -0.0762 4.048506 0)
			(unlocked yes)
			(layer "Cmts.User")
			(hide yes)
			(effects
				(font
					(size 0.7874 0.5842)
					(thickness 0.1524)
				)
				(justify mirror)
			)
		)
		(duplicate_pad_numbers_are_jumpers no)
		(fp_line
			(start -1.5748 -0.9398)
			(end 1.5748 -0.9398)
			(stroke
				(width 0.1)
				(type default)
			)
			(layer "B.SilkS")
		)
		(fp_line
			(start -1.5748 0.9398)
			(end -1.5748 -0.9398)
			(stroke
				(width 0.1)
				(type default)
			)
			(layer "B.SilkS")
		)
		(fp_line
			(start 1.5748 -0.9398)
			(end 1.5748 0.9398)
			(stroke
				(width 0.1)
				(type default)
			)
			(layer "B.SilkS")
		)
		(fp_line
			(start 1.5748 0.9398)
			(end -1.5748 0.9398)
			(stroke
				(width 0.1)
				(type default)
			)
			(layer "B.SilkS")
		)
		(fp_rect
			(start 1.5748 -0.9398)
			(end -1.5748 0.9398)
			(stroke
				(width 0)
				(type default)
			)
			(fill no)
			(layer "B.CrtYd")
		)
		(fp_line
			(start -1.016 -0.635)
			(end 1.016 -0.635)
			(stroke
				(width 0.1)
				(type default)
			)
			(layer "B.Fab")
		)
		(fp_line
			(start -1.016 0.635)
			(end -1.016 -0.635)
			(stroke
				(width 0.1)
				(type default)
			)
			(layer "B.Fab")
		)
		(fp_line
			(start 1.016 -0.635)
			(end 1.016 0.635)
			(stroke
				(width 0.1)
				(type default)
			)
			(layer "B.Fab")
		)
		(fp_line
			(start 1.016 0.635)
			(end -1.016 0.635)
			(stroke
				(width 0.1)
				(type default)
			)
			(layer "B.Fab")
		)
		(pad "1" smd rect
			(at 0.8382 0 180)
			(size 0.9652 1.3716)
			(layers "B.Cu" "B.Mask" "B.Paste")
			(net "XP3R3V_FPGA")
		)
		(pad "2" smd rect
			(at -0.8382 0 180)
			(size 0.9652 1.3716)
			(layers "B.Cu" "B.Mask" "B.Paste")
			(net "SG")
		)
		(zone
			(layer "B.Cu")
			(hatch none 0.5)
			(connect_pads
				(clearance 0)
			)
			(min_thickness 0.25)
			(keepout
				(tracks allowed)
				(vias not_allowed)
				(pads allowed)
				(copperpour not_allowed)
				(footprints allowed)
			)
			(placement
				(enabled no)
				(sheetname "")
			)
			(fill
				(thermal_gap 0.5)
				(thermal_bridge_width 0.5)
				(island_removal_mode 0)
			)
			(polygon
				(pts
					(xy 106.0704 -73.152) (xy 105.6132 -73.152) (xy 105.6132 -71.882) (xy 106.0704 -71.882)
				)
			)
		)
	)
)
